(kicad_pcb
	(version 20260206)
	(generator "pcbnew")
	(generator_version "10.0")
	(general
		(thickness 1.6)
		(legacy_teardrops no)
	)
	(paper "A4")
	(title_block
		(title "03242023_DA0F0TMBIJ0_F0T_Motherboard_J_brd_V01_OCP.brd")
		(comment 1 "Grand Teton / footprint 1682 of 6105 (U1), pads 3791-3900 of 4677")
	)
	(layers
		(0 "F.Cu" signal "TOP")
		(4 "In1.Cu" signal "GND")
		(6 "In2.Cu" signal "IN1")
		(8 "In3.Cu" signal "GND1")
		(10 "In4.Cu" signal "IN2")
		(12 "In5.Cu" signal "GND2")
		(14 "In6.Cu" signal "IN3")
		(16 "In7.Cu" signal "GND3")
		(18 "In8.Cu" signal "VCC")
		(20 "In9.Cu" signal "VCC1")
		(22 "In10.Cu" signal "GND4")
		(24 "In11.Cu" signal "IN4")
		(26 "In12.Cu" signal "GND5")
		(28 "In13.Cu" signal "IN5")
		(30 "In14.Cu" signal "GND6")
		(32 "In15.Cu" signal "IN6")
		(34 "In16.Cu" signal "GND7")
		(2 "B.Cu" signal "BOTTOM")
		(9 "F.Adhes" user "F.Adhesive")
		(11 "B.Adhes" user "B.Adhesive")
		(13 "F.Paste" user "Package Geometry/Pastemask Top")
		(15 "B.Paste" user "Package Geometry/Pastemask Bottom")
		(5 "F.SilkS" user "Ref Des/Silkscreen Top")
		(7 "B.SilkS" user "Ref Des/Silkscreen Bottom")
		(1 "F.Mask" user "Board Geometry/Soldermask Top")
		(3 "B.Mask" user "Board Geometry/Soldermask Bottom")
		(17 "Dwgs.User" user "User.Drawings")
		(19 "Cmts.User" user "User.Comments")
		(21 "Eco1.User" user "User.Eco1")
		(23 "Eco2.User" user "User.Eco2")
		(25 "Edge.Cuts" user "Board Geometry/Outline")
		(27 "Margin" user)
		(31 "F.CrtYd" user "Package Geometry/Place Bound Top")
		(29 "B.CrtYd" user "Package Geometry/Place Bound Bottom")
		(35 "F.Fab" user "Ref Des/Assembly Top")
		(33 "B.Fab" user "Ref Des/Assembly Bottom")
	)
	(footprint ""
		(layer "F.Cu")
		(at 111.93018 -251.76988 90)
		(property "Reference" "U1"
			(at -74.913236 41.548812 0)
			(unlocked yes)
			(layer "F.SilkS")
			(effects
				(font
					(size 1.6002 1.1938)
					(thickness 0.1524)
				)
				(justify left)
			)
		)
		(property "Value" ""
			(at 0 0 90)
			(layer "F.Fab")
			(effects
				(font
					(size 1.27 1.27)
				)
			)
		)
		(duplicate_pad_numbers_are_jumpers no)
		(pad "EL31" smd circle
			(at -13.008356 24.614886 270)
			(size 0.4318 0.4318)
			(layers "F.Cu" "F.Mask" "F.Paste")
			(net "M_E_CPU1_SB_DQ<9>")
		)
		(pad "EL33" smd circle
			(at -11.380724 24.614886 270)
			(size 0.4318 0.4318)
			(layers "F.Cu" "F.Mask" "F.Paste")
			(net "GND")
		)
		(pad "EL35" smd circle
			(at -9.752838 24.614886 270)
			(size 0.4318 0.4318)
			(layers "F.Cu" "F.Mask" "F.Paste")
			(net "M_E_CPU1_SB_CB<0>")
		)
		(pad "EL37" smd circle
			(at -8.124952 24.614886 270)
			(size 0.4318 0.4318)
			(layers "F.Cu" "F.Mask" "F.Paste")
			(net "M_E_CPU1_SB_CB<5>")
		)
		(pad "EL39" smd circle
			(at -6.49732 24.614886 270)
			(size 0.4318 0.4318)
			(layers "F.Cu" "F.Mask" "F.Paste")
			(net "GND")
		)
		(pad "EL41" smd circle
			(at -4.869434 24.614886 270)
			(size 0.4318 0.4318)
			(layers "F.Cu" "F.Mask" "F.Paste")
			(net "M_E_CPU1_SB_CS_N<3>")
		)
		(pad "EL43" smd circle
			(at -3.241802 24.614886 270)
			(size 0.4318 0.4318)
			(layers "F.Cu" "F.Mask" "F.Paste")
			(net "M_E_CPU1_SB_CA<4>")
		)
		(pad "EL45" smd circle
			(at -1.613916 24.614886 270)
			(size 0.4318 0.4318)
			(layers "F.Cu" "F.Mask" "F.Paste")
			(net "GND")
		)
		(pad "EL48" smd circle
			(at 2.427732 24.724868 270)
			(size 0.4318 0.4318)
			(layers "F.Cu" "F.Mask" "F.Paste")
			(net "M_E_CPU1_SA_CA<3>")
		)
		(pad "EL50" smd circle
			(at 4.055618 24.724868 270)
			(size 0.4318 0.4318)
			(layers "F.Cu" "F.Mask" "F.Paste")
			(net "M_E_CPU1_SA_CS_N<3>")
		)
		(pad "EL52" smd circle
			(at 5.68325 24.724868 270)
			(size 0.4318 0.4318)
			(layers "F.Cu" "F.Mask" "F.Paste")
			(net "GND")
		)
		(pad "EL54" smd circle
			(at 7.311136 24.724868 270)
			(size 0.4318 0.4318)
			(layers "F.Cu" "F.Mask" "F.Paste")
			(net "M_E_CPU1_SA_CB<4>")
		)
		(pad "EL56" smd circle
			(at 8.939022 24.724868 270)
			(size 0.4318 0.4318)
			(layers "F.Cu" "F.Mask" "F.Paste")
			(net "M_E_CPU1_SA_CB<1>")
		)
		(pad "EL58" smd circle
			(at 10.566654 24.724868 270)
			(size 0.4318 0.4318)
			(layers "F.Cu" "F.Mask" "F.Paste")
			(net "GND")
		)
		(pad "EL60" smd circle
			(at 12.19454 24.724868 270)
			(size 0.4318 0.4318)
			(layers "F.Cu" "F.Mask" "F.Paste")
			(net "M_E_CPU1_SA_DQ<28>")
		)
		(pad "EL62" smd circle
			(at 13.822426 24.724868 270)
			(size 0.4318 0.4318)
			(layers "F.Cu" "F.Mask" "F.Paste")
			(net "M_E_CPU1_SA_DQ<25>")
		)
		(pad "EL64" smd circle
			(at 15.450058 24.724868 270)
			(size 0.4318 0.4318)
			(layers "F.Cu" "F.Mask" "F.Paste")
			(net "GND")
		)
		(pad "EL66" smd circle
			(at 17.07769 24.724868 270)
			(size 0.4318 0.4318)
			(layers "F.Cu" "F.Mask" "F.Paste")
			(net "M_E_CPU1_SA_DQ<22>")
		)
		(pad "EL68" smd circle
			(at 18.705576 24.724868 270)
			(size 0.4318 0.4318)
			(layers "F.Cu" "F.Mask" "F.Paste")
			(net "M_E_CPU1_SA_DQS_DP<2>")
		)
		(pad "EL70" smd circle
			(at 20.333462 24.724868 270)
			(size 0.4318 0.4318)
			(layers "F.Cu" "F.Mask" "F.Paste")
			(net "GND")
		)
		(pad "EL72" smd circle
			(at 21.961094 24.724868 270)
			(size 0.4318 0.4318)
			(layers "F.Cu" "F.Mask" "F.Paste")
			(net "GND")
		)
		(pad "EL74" smd circle
			(at 23.58898 24.724868 270)
			(size 0.4318 0.4318)
			(layers "F.Cu" "F.Mask" "F.Paste")
			(net "M_E_CPU1_SA_DQ<4>")
		)
		(pad "EL76" smd circle
			(at 25.216612 24.724868 270)
			(size 0.4318 0.4318)
			(layers "F.Cu" "F.Mask" "F.Paste")
			(net "GND")
		)
		(pad "EL78" smd circle
			(at 26.844498 24.724868 270)
			(size 0.4318 0.4318)
			(layers "F.Cu" "F.Mask" "F.Paste")
			(net "M_E_CPU1_SA_DQ<0>")
		)
		(pad "EL80" smd circle
			(at 28.472384 24.724868 270)
			(size 0.4318 0.4318)
			(layers "F.Cu" "F.Mask" "F.Paste")
			(net "GND")
		)
		(pad "EL82" smd circle
			(at 30.100016 24.724868 270)
			(size 0.4318 0.4318)
			(layers "F.Cu" "F.Mask" "F.Paste")
			(net "GND")
		)
		(pad "EL84" smd circle
			(at 31.727902 24.724868 270)
			(size 0.4318 0.4318)
			(layers "F.Cu" "F.Mask" "F.Paste")
			(net "Net_748")
		)
		(pad "EL86" smd oval
			(at 33.355534 24.724868 315)
			(size 0.381 0.4826)
			(drill
				(offset 0 -0.0508)
			)
			(layers "F.Cu" "F.Mask" "F.Paste")
			(net "GND")
		)
		(pad "EL88" smd oval
			(at 34.98342 24.724868 315)
			(size 0.381 0.4826)
			(drill
				(offset 0 -0.0508)
			)
			(layers "F.Cu" "F.Mask" "F.Paste")
			(net "Net_706")
		)
		(pad "EM4" smd oval
			(at -34.98342 25.084532 225)
			(size 0.381 0.4826)
			(drill
				(offset 0 -0.0508)
			)
			(layers "F.Cu" "F.Mask" "F.Paste")
			(net "M_G_CPU1_SB_DQ<31>")
		)
		(pad "EM6" smd oval
			(at -33.355534 25.084532 225)
			(size 0.381 0.4826)
			(drill
				(offset 0 -0.0508)
			)
			(layers "F.Cu" "F.Mask" "F.Paste")
			(net "M_G_CPU1_SB_DQS_DN<8>")
		)
		(pad "EM8" smd circle
			(at -31.727902 25.084532 270)
			(size 0.4318 0.4318)
			(layers "F.Cu" "F.Mask" "F.Paste")
			(net "GND")
		)
		(pad "EM10" smd circle
			(at -30.100016 25.084532 270)
			(size 0.4318 0.4318)
			(layers "F.Cu" "F.Mask" "F.Paste")
			(net "M_F_CPU1_SB_DQ<21>")
		)
		(pad "EM12" smd circle
			(at -28.472384 25.084532 270)
			(size 0.4318 0.4318)
			(layers "F.Cu" "F.Mask" "F.Paste")
			(net "M_F_CPU1_SB_DQS_DN<2>")
		)
		(pad "EM14" smd circle
			(at -26.844498 25.084532 270)
			(size 0.4318 0.4318)
			(layers "F.Cu" "F.Mask" "F.Paste")
			(net "M_F_CPU1_SB_DQ<16>")
		)
		(pad "EM16" smd circle
			(at -25.216612 25.084532 270)
			(size 0.4318 0.4318)
			(layers "F.Cu" "F.Mask" "F.Paste")
			(net "M_E_CPU1_SB_DQ<29>")
		)
		(pad "EM18" smd circle
			(at -23.58898 25.084532 270)
			(size 0.4318 0.4318)
			(layers "F.Cu" "F.Mask" "F.Paste")
			(net "M_E_CPU1_SB_DQS_DP<3>")
		)
		(pad "EM20" smd circle
			(at -21.961094 25.084532 270)
			(size 0.4318 0.4318)
			(layers "F.Cu" "F.Mask" "F.Paste")
			(net "M_E_CPU1_SB_DQ<24>")
		)
		(pad "EM22" smd circle
			(at -20.333462 25.084532 270)
			(size 0.4318 0.4318)
			(layers "F.Cu" "F.Mask" "F.Paste")
			(net "M_E_CPU1_SB_DQ<21>")
		)
		(pad "EM24" smd circle
			(at -18.705576 25.084532 270)
			(size 0.4318 0.4318)
			(layers "F.Cu" "F.Mask" "F.Paste")
			(net "M_E_CPU1_SB_DQS_DP<2>")
		)
		(pad "EM26" smd circle
			(at -17.07769 25.084532 270)
			(size 0.4318 0.4318)
			(layers "F.Cu" "F.Mask" "F.Paste")
			(net "M_E_CPU1_SB_DQ<16>")
		)
		(pad "EM28" smd circle
			(at -15.450058 25.084532 270)
			(size 0.4318 0.4318)
			(layers "F.Cu" "F.Mask" "F.Paste")
			(net "M_E_CPU1_SB_DQ<13>")
		)
		(pad "EM30" smd circle
			(at -13.822426 25.084532 270)
			(size 0.4318 0.4318)
			(layers "F.Cu" "F.Mask" "F.Paste")
			(net "M_E_CPU1_SB_DQS_DP<1>")
		)
		(pad "EM32" smd circle
			(at -12.19454 25.084532 270)
			(size 0.4318 0.4318)
			(layers "F.Cu" "F.Mask" "F.Paste")
			(net "M_E_CPU1_SB_DQ<8>")
		)
		(pad "EM34" smd circle
			(at -10.566654 25.084532 270)
			(size 0.4318 0.4318)
			(layers "F.Cu" "F.Mask" "F.Paste")
			(net "M_E_CPU1_SB_CB<1>")
		)
		(pad "EM36" smd circle
			(at -8.939022 25.084532 270)
			(size 0.4318 0.4318)
			(layers "F.Cu" "F.Mask" "F.Paste")
			(net "M_E_CPU1_SB_DQS_DP<9>")
		)
		(pad "EM38" smd circle
			(at -7.311136 25.084532 270)
			(size 0.4318 0.4318)
			(layers "F.Cu" "F.Mask" "F.Paste")
			(net "M_E_CPU1_SB_CB<4>")
		)
		(pad "EM40" smd circle
			(at -5.68325 25.084532 270)
			(size 0.4318 0.4318)
			(layers "F.Cu" "F.Mask" "F.Paste")
			(net "M_E_CPU1_SB_CS_N<2>")
		)
		(pad "EM42" smd circle
			(at -4.055618 25.084532 270)
			(size 0.4318 0.4318)
			(layers "F.Cu" "F.Mask" "F.Paste")
			(net "GND")
		)
		(pad "EM44" smd circle
			(at -2.427732 25.084532 270)
			(size 0.4318 0.4318)
			(layers "F.Cu" "F.Mask" "F.Paste")
			(net "M_E_CPU1_SB_CA<2>")
		)
		(pad "EM47" smd circle
			(at 1.613916 25.194514 270)
			(size 0.4318 0.4318)
			(layers "F.Cu" "F.Mask" "F.Paste")
			(net "M_E_CPU1_SA_CA<4>")
		)
		(pad "EM49" smd circle
			(at 3.241802 25.194514 270)
			(size 0.4318 0.4318)
			(layers "F.Cu" "F.Mask" "F.Paste")
			(net "GND")
		)
		(pad "EM51" smd circle
			(at 4.869434 25.194514 270)
			(size 0.4318 0.4318)
			(layers "F.Cu" "F.Mask" "F.Paste")
			(net "M_E_CPU1_SA_CS_N<2>")
		)
		(pad "EM53" smd circle
			(at 6.49732 25.194514 270)
			(size 0.4318 0.4318)
			(layers "F.Cu" "F.Mask" "F.Paste")
			(net "M_E_CPU1_SA_CB<5>")
		)
		(pad "EM55" smd circle
			(at 8.124952 25.194514 270)
			(size 0.4318 0.4318)
			(layers "F.Cu" "F.Mask" "F.Paste")
			(net "M_E_CPU1_SA_DQS_DN<4>")
		)
		(pad "EM57" smd circle
			(at 9.752838 25.194514 270)
			(size 0.4318 0.4318)
			(layers "F.Cu" "F.Mask" "F.Paste")
			(net "M_E_CPU1_SA_CB<0>")
		)
		(pad "EM59" smd circle
			(at 11.380724 25.194514 270)
			(size 0.4318 0.4318)
			(layers "F.Cu" "F.Mask" "F.Paste")
			(net "M_E_CPU1_SA_DQ<29>")
		)
		(pad "EM61" smd circle
			(at 13.008356 25.194514 270)
			(size 0.4318 0.4318)
			(layers "F.Cu" "F.Mask" "F.Paste")
			(net "M_E_CPU1_SA_DQS_DP<3>")
		)
		(pad "EM63" smd circle
			(at 14.635988 25.194514 270)
			(size 0.4318 0.4318)
			(layers "F.Cu" "F.Mask" "F.Paste")
			(net "M_E_CPU1_SA_DQ<24>")
		)
		(pad "EM65" smd circle
			(at 16.263874 25.194514 270)
			(size 0.4318 0.4318)
			(layers "F.Cu" "F.Mask" "F.Paste")
			(net "M_E_CPU1_SA_DQ<21>")
		)
		(pad "EM67" smd circle
			(at 17.89176 25.194514 270)
			(size 0.4318 0.4318)
			(layers "F.Cu" "F.Mask" "F.Paste")
			(net "M_E_CPU1_SA_DQS_DP<7>")
		)
		(pad "EM69" smd circle
			(at 19.519392 25.194514 270)
			(size 0.4318 0.4318)
			(layers "F.Cu" "F.Mask" "F.Paste")
			(net "M_E_CPU1_SA_DQ<17>")
		)
		(pad "EM71" smd circle
			(at 21.147278 25.194514 270)
			(size 0.4318 0.4318)
			(layers "F.Cu" "F.Mask" "F.Paste")
			(net "M_E_CPU1_SA_DQ<16>")
		)
		(pad "EM73" smd circle
			(at 22.77491 25.194514 270)
			(size 0.4318 0.4318)
			(layers "F.Cu" "F.Mask" "F.Paste")
			(net "GND")
		)
		(pad "EM75" smd circle
			(at 24.402796 25.194514 270)
			(size 0.4318 0.4318)
			(layers "F.Cu" "F.Mask" "F.Paste")
			(net "M_E_CPU1_SA_DQS_DN<5>")
		)
		(pad "EM77" smd circle
			(at 26.030682 25.194514 270)
			(size 0.4318 0.4318)
			(layers "F.Cu" "F.Mask" "F.Paste")
			(net "M_E_CPU1_SA_DQ<1>")
		)
		(pad "EM79" smd circle
			(at 27.658314 25.194514 270)
			(size 0.4318 0.4318)
			(layers "F.Cu" "F.Mask" "F.Paste")
			(net "GND")
		)
		(pad "EM81" smd circle
			(at 29.2862 25.194514 270)
			(size 0.4318 0.4318)
			(layers "F.Cu" "F.Mask" "F.Paste")
			(net "GND")
		)
		(pad "EM83" smd circle
			(at 30.914086 25.194514 270)
			(size 0.4318 0.4318)
			(layers "F.Cu" "F.Mask" "F.Paste")
			(net "GND")
		)
		(pad "EM85" smd oval
			(at 32.541718 25.194514 315)
			(size 0.381 0.4826)
			(drill
				(offset 0 -0.0508)
			)
			(layers "F.Cu" "F.Mask" "F.Paste")
			(net "Net_724")
		)
		(pad "EM87" smd oval
			(at 34.169604 25.194514 315)
			(size 0.381 0.4826)
			(drill
				(offset 0 -0.0508)
			)
			(layers "F.Cu" "F.Mask" "F.Paste")
			(net "Net_732")
		)
		(pad "EN5" smd oval
			(at -34.169604 25.554686 225)
			(size 0.381 0.4826)
			(drill
				(offset 0 -0.0508)
			)
			(layers "F.Cu" "F.Mask" "F.Paste")
			(net "M_G_CPU1_SB_DQS_DP<8>")
		)
		(pad "EN7" smd oval
			(at -32.541718 25.554686 225)
			(size 0.381 0.4826)
			(drill
				(offset 0 -0.0508)
			)
			(layers "F.Cu" "F.Mask" "F.Paste")
			(net "M_G_CPU1_SB_DQS_DP<3>")
		)
		(pad "EN9" smd circle
			(at -30.914086 25.554686 270)
			(size 0.4318 0.4318)
			(layers "F.Cu" "F.Mask" "F.Paste")
			(net "GND")
		)
		(pad "EN11" smd circle
			(at -29.2862 25.554686 270)
			(size 0.4318 0.4318)
			(layers "F.Cu" "F.Mask" "F.Paste")
			(net "GND")
		)
		(pad "EN13" smd circle
			(at -27.658314 25.554686 270)
			(size 0.4318 0.4318)
			(layers "F.Cu" "F.Mask" "F.Paste")
			(net "GND")
		)
		(pad "EN15" smd circle
			(at -26.030682 25.554686 270)
			(size 0.4318 0.4318)
			(layers "F.Cu" "F.Mask" "F.Paste")
			(net "GND")
		)
		(pad "EN17" smd circle
			(at -24.402796 25.554686 270)
			(size 0.4318 0.4318)
			(layers "F.Cu" "F.Mask" "F.Paste")
			(net "GND")
		)
		(pad "EN19" smd circle
			(at -22.77491 25.554686 270)
			(size 0.4318 0.4318)
			(layers "F.Cu" "F.Mask" "F.Paste")
			(net "GND")
		)
		(pad "EN21" smd circle
			(at -21.147278 25.554686 270)
			(size 0.4318 0.4318)
			(layers "F.Cu" "F.Mask" "F.Paste")
			(net "GND")
		)
		(pad "EN23" smd circle
			(at -19.519392 25.554686 270)
			(size 0.4318 0.4318)
			(layers "F.Cu" "F.Mask" "F.Paste")
			(net "GND")
		)
		(pad "EN25" smd circle
			(at -17.89176 25.554686 270)
			(size 0.4318 0.4318)
			(layers "F.Cu" "F.Mask" "F.Paste")
			(net "GND")
		)
		(pad "EN27" smd circle
			(at -16.263874 25.554686 270)
			(size 0.4318 0.4318)
			(layers "F.Cu" "F.Mask" "F.Paste")
			(net "GND")
		)
		(pad "EN29" smd circle
			(at -14.635988 25.554686 270)
			(size 0.4318 0.4318)
			(layers "F.Cu" "F.Mask" "F.Paste")
			(net "GND")
		)
		(pad "EN31" smd circle
			(at -13.008356 25.554686 270)
			(size 0.4318 0.4318)
			(layers "F.Cu" "F.Mask" "F.Paste")
			(net "GND")
		)
		(pad "EN33" smd circle
			(at -11.380724 25.554686 270)
			(size 0.4318 0.4318)
			(layers "F.Cu" "F.Mask" "F.Paste")
			(net "GND")
		)
		(pad "EN35" smd circle
			(at -9.752838 25.554686 270)
			(size 0.4318 0.4318)
			(layers "F.Cu" "F.Mask" "F.Paste")
			(net "GND")
		)
		(pad "EN37" smd circle
			(at -8.124952 25.554686 270)
			(size 0.4318 0.4318)
			(layers "F.Cu" "F.Mask" "F.Paste")
			(net "GND")
		)
		(pad "EN39" smd circle
			(at -6.49732 25.554686 270)
			(size 0.4318 0.4318)
			(layers "F.Cu" "F.Mask" "F.Paste")
			(net "GND")
		)
		(pad "EN41" smd circle
			(at -4.869434 25.554686 270)
			(size 0.4318 0.4318)
			(layers "F.Cu" "F.Mask" "F.Paste")
			(net "GND")
		)
		(pad "EN43" smd circle
			(at -3.241802 25.554686 270)
			(size 0.4318 0.4318)
			(layers "F.Cu" "F.Mask" "F.Paste")
			(net "GND")
		)
		(pad "EN45" smd oval
			(at -1.613916 25.554686 270)
			(size 0.381 0.4826)
			(drill
				(offset 0 -0.0508)
			)
			(layers "F.Cu" "F.Mask" "F.Paste")
			(net "GND")
		)
		(pad "EN48" smd circle
			(at 2.427732 25.664414 270)
			(size 0.4318 0.4318)
			(layers "F.Cu" "F.Mask" "F.Paste")
			(net "GND")
		)
		(pad "EN50" smd circle
			(at 4.055618 25.664414 270)
			(size 0.4318 0.4318)
			(layers "F.Cu" "F.Mask" "F.Paste")
			(net "GND")
		)
		(pad "EN52" smd circle
			(at 5.68325 25.664414 270)
			(size 0.4318 0.4318)
			(layers "F.Cu" "F.Mask" "F.Paste")
			(net "GND")
		)
		(pad "EN54" smd circle
			(at 7.311136 25.664414 270)
			(size 0.4318 0.4318)
			(layers "F.Cu" "F.Mask" "F.Paste")
			(net "GND")
		)
		(pad "EN56" smd circle
			(at 8.939022 25.664414 270)
			(size 0.4318 0.4318)
			(layers "F.Cu" "F.Mask" "F.Paste")
			(net "GND")
		)
		(pad "EN58" smd circle
			(at 10.566654 25.664414 270)
			(size 0.4318 0.4318)
			(layers "F.Cu" "F.Mask" "F.Paste")
			(net "GND")
		)
		(pad "EN60" smd circle
			(at 12.19454 25.664414 270)
			(size 0.4318 0.4318)
			(layers "F.Cu" "F.Mask" "F.Paste")
			(net "GND")
		)
		(pad "EN62" smd circle
			(at 13.822426 25.664414 270)
			(size 0.4318 0.4318)
			(layers "F.Cu" "F.Mask" "F.Paste")
			(net "GND")
		)
		(pad "EN64" smd circle
			(at 15.450058 25.664414 270)
			(size 0.4318 0.4318)
			(layers "F.Cu" "F.Mask" "F.Paste")
			(net "GND")
		)
		(pad "EN66" smd circle
			(at 17.07769 25.664414 270)
			(size 0.4318 0.4318)
			(layers "F.Cu" "F.Mask" "F.Paste")
			(net "GND")
		)
		(pad "EN68" smd circle
			(at 18.705576 25.664414 270)
			(size 0.4318 0.4318)
			(layers "F.Cu" "F.Mask" "F.Paste")
			(net "M_E_CPU1_SA_DQS_DN<7>")
		)
		(pad "EN70" smd circle
			(at 20.333462 25.664414 270)
			(size 0.4318 0.4318)
			(layers "F.Cu" "F.Mask" "F.Paste")
			(net "M_E_CPU1_SA_DQ<18>")
		)
		(pad "EN72" smd circle
			(at 21.961094 25.664414 270)
			(size 0.4318 0.4318)
			(layers "F.Cu" "F.Mask" "F.Paste")
			(net "GND")
		)
		(pad "EN74" smd circle
			(at 23.58898 25.664414 270)
			(size 0.4318 0.4318)
			(layers "F.Cu" "F.Mask" "F.Paste")
			(net "M_E_CPU1_SA_DQS_DP<5>")
		)
		(pad "EN76" smd circle
			(at 25.216612 25.664414 270)
			(size 0.4318 0.4318)
			(layers "F.Cu" "F.Mask" "F.Paste")
			(net "M_E_CPU1_SA_DQS_DP<0>")
		)
		(pad "EN78" smd circle
			(at 26.844498 25.664414 270)
			(size 0.4318 0.4318)
			(layers "F.Cu" "F.Mask" "F.Paste")
			(net "GND")
		)
		(pad "EN80" smd circle
			(at 28.472384 25.664414 270)
			(size 0.4318 0.4318)
			(layers "F.Cu" "F.Mask" "F.Paste")
			(net "GND")
		)
		(pad "EN82" smd circle
			(at 30.100016 25.664414 270)
			(size 0.4318 0.4318)
			(layers "F.Cu" "F.Mask" "F.Paste")
			(net "GND")
		)
	)
)
